(kicad_pcb
	(version 20260206)
	(generator "pcbnew")
	(generator_version "10.0")
	(general
		(thickness 1.6)
		(legacy_teardrops no)
	)
	(paper "A4")
	(title_block
		(title "01162023_DA0F0TEBIF0_F0T_Expander_BD_F_brd_V02_OCP.brd")
		(comment 1 "Grand Teton / footprints 4426-4430 of 9728")
	)
	(layers
		(0 "F.Cu" signal "TOP")
		(4 "In1.Cu" signal "GND")
		(6 "In2.Cu" signal "VCC")
		(8 "In3.Cu" signal "VCC1")
		(10 "In4.Cu" signal "GND1")
		(12 "In5.Cu" signal "IN1")
		(14 "In6.Cu" signal "GND2")
		(16 "In7.Cu" signal "IN2")
		(18 "In8.Cu" signal "GND3")
		(20 "In9.Cu" signal "IN3")
		(22 "In10.Cu" signal "GND4")
		(24 "In11.Cu" signal "IN4")
		(26 "In12.Cu" signal "GND5")
		(28 "In13.Cu" signal "IN5")
		(30 "In14.Cu" signal "GND6")
		(32 "In15.Cu" signal "IN6")
		(34 "In16.Cu" signal "GND7")
		(2 "B.Cu" signal "BOTTOM")
		(9 "F.Adhes" user "F.Adhesive")
		(11 "B.Adhes" user "B.Adhesive")
		(13 "F.Paste" user "Package Geometry/Pastemask Top")
		(15 "B.Paste" user "Package Geometry/Pastemask Bottom")
		(5 "F.SilkS" user "Ref Des/Silkscreen Top")
		(7 "B.SilkS" user "Ref Des/Silkscreen Bottom")
		(1 "F.Mask" user "Board Geometry/Soldermask Top")
		(3 "B.Mask" user "Board Geometry/Soldermask Bottom")
		(17 "Dwgs.User" user "User.Drawings")
		(19 "Cmts.User" user "User.Comments")
		(21 "Eco1.User" user "User.Eco1")
		(23 "Eco2.User" user "User.Eco2")
		(25 "Edge.Cuts" user "Board Geometry/Outline")
		(27 "Margin" user)
		(31 "F.CrtYd" user "Package Geometry/Place Bound Top")
		(29 "B.CrtYd" user "Package Geometry/Place Bound Bottom")
		(35 "F.Fab" user "Ref Des/Assembly Top")
		(33 "B.Fab" user "Ref Des/Assembly Bottom")
	)
	(footprint ""
		(layer "F.Cu")
		(at 330.63434 -34.546286 180)
		(property "Reference" "C511"
			(at 0 0 180)
			(layer "F.SilkS")
			(hide yes)
			(effects
				(font
					(size 1.27 1.27)
				)
			)
		)
		(property "Value" ""
			(at 0 0 180)
			(layer "F.Fab")
			(effects
				(font
					(size 1.27 1.27)
				)
			)
		)
		(duplicate_pad_numbers_are_jumpers no)
		(fp_line
			(start 0.299974 0.150114)
			(end -0.299974 0.150114)
			(stroke
				(width 0.1)
				(type default)
			)
			(layer "F.Fab")
		)
		(fp_line
			(start 0.299974 -0.150114)
			(end 0.299974 0.150114)
			(stroke
				(width 0.1)
				(type default)
			)
			(layer "F.Fab")
		)
		(fp_line
			(start -0.299974 0.150114)
			(end -0.299974 -0.150114)
			(stroke
				(width 0.1)
				(type default)
			)
			(layer "F.Fab")
		)
		(fp_line
			(start -0.299974 -0.150114)
			(end 0.299974 -0.150114)
			(stroke
				(width 0.1)
				(type default)
			)
			(layer "F.Fab")
		)
		(pad "1" smd rect
			(at -0.2667 0 180)
			(size 0.3048 0.381)
			(layers "F.Cu" "F.Mask" "F.Paste")
			(net "P5E_PEX2_STN2_TX_DP<35>")
		)
		(pad "2" smd rect
			(at 0.2667 0 180)
			(size 0.3048 0.381)
			(layers "F.Cu" "F.Mask" "F.Paste")
			(net "P5E_PEX2_STN2_TX_C_DP<35>")
		)
	)
	(footprint ""
		(layer "F.Cu")
		(at 224.695512 -231.416606 90)
		(property "Reference" "R4544"
			(at 0 0 90)
			(layer "F.SilkS")
			(hide yes)
			(effects
				(font
					(size 1.27 1.27)
				)
			)
		)
		(property "Value" ""
			(at 0 0 90)
			(layer "F.Fab")
			(effects
				(font
					(size 1.27 1.27)
				)
			)
		)
		(duplicate_pad_numbers_are_jumpers no)
		(fp_line
			(start 0.7874 -0.4064)
			(end 0.7874 0.4064)
			(stroke
				(width 0.1524)
				(type default)
			)
			(layer "F.SilkS")
		)
		(fp_line
			(start -0.7874 -0.4064)
			(end 0.7874 -0.4064)
			(stroke
				(width 0.1524)
				(type default)
			)
			(layer "F.SilkS")
		)
		(fp_line
			(start 0.7874 0.4064)
			(end -0.7874 0.4064)
			(stroke
				(width 0.1524)
				(type default)
			)
			(layer "F.SilkS")
		)
		(fp_line
			(start -0.7874 0.4064)
			(end -0.7874 -0.4064)
			(stroke
				(width 0.1524)
				(type default)
			)
			(layer "F.SilkS")
		)
		(fp_line
			(start -0.12065 -0.305054)
			(end -0.12065 -0.2794)
			(stroke
				(width 0.1)
				(type default)
			)
			(layer "F.Fab")
		)
		(fp_line
			(start -0.67945 -0.305054)
			(end -0.12065 -0.305054)
			(stroke
				(width 0.1)
				(type default)
			)
			(layer "F.Fab")
		)
		(fp_line
			(start 0.67945 -0.3048)
			(end 0.67945 0.3048)
			(stroke
				(width 0.1)
				(type default)
			)
			(layer "F.Fab")
		)
		(fp_line
			(start 0.12065 -0.3048)
			(end 0.67945 -0.3048)
			(stroke
				(width 0.1)
				(type default)
			)
			(layer "F.Fab")
		)
		(fp_line
			(start 0.12065 -0.2794)
			(end 0.12065 -0.3048)
			(stroke
				(width 0.1)
				(type default)
			)
			(layer "F.Fab")
		)
		(fp_line
			(start -0.12065 -0.2794)
			(end 0.12065 -0.2794)
			(stroke
				(width 0.1)
				(type default)
			)
			(layer "F.Fab")
		)
		(fp_line
			(start 0.120396 0.2794)
			(end -0.12065 0.2794)
			(stroke
				(width 0.1)
				(type default)
			)
			(layer "F.Fab")
		)
		(fp_line
			(start -0.12065 0.2794)
			(end -0.12065 0.3048)
			(stroke
				(width 0.1)
				(type default)
			)
			(layer "F.Fab")
		)
		(fp_line
			(start 0.67945 0.3048)
			(end 0.120396 0.3048)
			(stroke
				(width 0.1)
				(type default)
			)
			(layer "F.Fab")
		)
		(fp_line
			(start 0.120396 0.3048)
			(end 0.120396 0.2794)
			(stroke
				(width 0.1)
				(type default)
			)
			(layer "F.Fab")
		)
		(fp_line
			(start -0.12065 0.3048)
			(end -0.67945 0.3048)
			(stroke
				(width 0.1)
				(type default)
			)
			(layer "F.Fab")
		)
		(fp_line
			(start -0.67945 0.3048)
			(end -0.67945 -0.305054)
			(stroke
				(width 0.1)
				(type default)
			)
			(layer "F.Fab")
		)
		(pad "1" smd circle
			(at -0.40005 0 90)
			(size 0 0)
			(layers "F.Cu" "F.Mask" "F.Paste")
			(net "REV_ID0")
		)
		(pad "2" smd circle
			(at 0.40005 0 90)
			(size 0 0)
			(layers "F.Cu" "F.Mask" "F.Paste")
			(net "P3V3_AUX")
		)
	)
	(footprint ""
		(layer "F.Cu")
		(at 259.130038 -300.406308 -90)
		(property "Reference" "C3367"
			(at 0 0 270)
			(layer "F.SilkS")
			(hide yes)
			(effects
				(font
					(size 1.27 1.27)
				)
			)
		)
		(property "Value" ""
			(at 0 0 270)
			(layer "F.Fab")
			(effects
				(font
					(size 1.27 1.27)
				)
			)
		)
		(duplicate_pad_numbers_are_jumpers no)
		(fp_line
			(start -1.2954 0.5842)
			(end -1.2954 -0.5842)
			(stroke
				(width 0.1524)
				(type default)
			)
			(layer "F.SilkS")
		)
		(fp_line
			(start 1.2954 0.5842)
			(end -1.2954 0.5842)
			(stroke
				(width 0.1524)
				(type default)
			)
			(layer "F.SilkS")
		)
		(fp_line
			(start -1.2954 -0.5842)
			(end 1.2954 -0.5842)
			(stroke
				(width 0.1524)
				(type default)
			)
			(layer "F.SilkS")
		)
		(fp_line
			(start 1.2954 -0.5842)
			(end 1.2954 0.5842)
			(stroke
				(width 0.1524)
				(type default)
			)
			(layer "F.SilkS")
		)
		(fp_line
			(start -0.8636 0.4572)
			(end -0.8636 0.4064)
			(stroke
				(width 0.1)
				(type default)
			)
			(layer "F.Fab")
		)
		(fp_line
			(start 0.8636 0.4572)
			(end -0.8636 0.4572)
			(stroke
				(width 0.1)
				(type default)
			)
			(layer "F.Fab")
		)
		(fp_line
			(start -1.1938 0.4064)
			(end -1.1938 -0.4064)
			(stroke
				(width 0.1)
				(type default)
			)
			(layer "F.Fab")
		)
		(fp_line
			(start -0.8636 0.4064)
			(end -1.1938 0.4064)
			(stroke
				(width 0.1)
				(type default)
			)
			(layer "F.Fab")
		)
		(fp_line
			(start 0.8636 0.4064)
			(end 0.8636 0.4572)
			(stroke
				(width 0.1)
				(type default)
			)
			(layer "F.Fab")
		)
		(fp_line
			(start 1.1938 0.4064)
			(end 0.8636 0.4064)
			(stroke
				(width 0.1)
				(type default)
			)
			(layer "F.Fab")
		)
		(fp_line
			(start -1.1938 -0.4064)
			(end -0.8636 -0.4064)
			(stroke
				(width 0.1)
				(type default)
			)
			(layer "F.Fab")
		)
		(fp_line
			(start -0.8636 -0.4064)
			(end -0.8636 -0.4572)
			(stroke
				(width 0.1)
				(type default)
			)
			(layer "F.Fab")
		)
		(fp_line
			(start 0.8636 -0.4064)
			(end 1.1938 -0.4064)
			(stroke
				(width 0.1)
				(type default)
			)
			(layer "F.Fab")
		)
		(fp_line
			(start 1.1938 -0.4064)
			(end 1.1938 0.4064)
			(stroke
				(width 0.1)
				(type default)
			)
			(layer "F.Fab")
		)
		(fp_line
			(start -0.8636 -0.4572)
			(end 0.8636 -0.4572)
			(stroke
				(width 0.1)
				(type default)
			)
			(layer "F.Fab")
		)
		(fp_line
			(start 0.8636 -0.4572)
			(end 0.8636 -0.4064)
			(stroke
				(width 0.1)
				(type default)
			)
			(layer "F.Fab")
		)
		(pad "1" smd rect
			(at -0.7366 0 180)
			(size 0.7112 0.8128)
			(layers "F.Cu" "F.Mask" "F.Paste")
			(net "P1V8_PLL0_PEX2")
		)
		(pad "2" smd rect
			(at 0.7366 0 180)
			(size 0.7112 0.8128)
			(layers "F.Cu" "F.Mask" "F.Paste")
			(net "GND")
		)
	)
	(footprint ""
		(layer "F.Cu")
		(at 370.071904 -259.346192)
		(property "Reference" "R1458"
			(at 0 0 0)
			(layer "F.SilkS")
			(hide yes)
			(effects
				(font
					(size 1.27 1.27)
				)
			)
		)
		(property "Value" ""
			(at 0 0 0)
			(layer "F.Fab")
			(effects
				(font
					(size 1.27 1.27)
				)
			)
		)
		(duplicate_pad_numbers_are_jumpers no)
		(fp_line
			(start -0.7874 -0.4064)
			(end 0.7874 -0.4064)
			(stroke
				(width 0.1524)
				(type default)
			)
			(layer "F.SilkS")
		)
		(fp_line
			(start -0.7874 0.4064)
			(end -0.7874 -0.4064)
			(stroke
				(width 0.1524)
				(type default)
			)
			(layer "F.SilkS")
		)
		(fp_line
			(start 0.7874 -0.4064)
			(end 0.7874 0.4064)
			(stroke
				(width 0.1524)
				(type default)
			)
			(layer "F.SilkS")
		)
		(fp_line
			(start 0.7874 0.4064)
			(end -0.7874 0.4064)
			(stroke
				(width 0.1524)
				(type default)
			)
			(layer "F.SilkS")
		)
		(fp_line
			(start -0.67945 -0.305054)
			(end -0.12065 -0.305054)
			(stroke
				(width 0.1)
				(type default)
			)
			(layer "F.Fab")
		)
		(fp_line
			(start -0.67945 0.3048)
			(end -0.67945 -0.305054)
			(stroke
				(width 0.1)
				(type default)
			)
			(layer "F.Fab")
		)
		(fp_line
			(start -0.12065 -0.305054)
			(end -0.12065 -0.2794)
			(stroke
				(width 0.1)
				(type default)
			)
			(layer "F.Fab")
		)
		(fp_line
			(start -0.12065 -0.2794)
			(end 0.12065 -0.2794)
			(stroke
				(width 0.1)
				(type default)
			)
			(layer "F.Fab")
		)
		(fp_line
			(start -0.12065 0.2794)
			(end -0.12065 0.3048)
			(stroke
				(width 0.1)
				(type default)
			)
			(layer "F.Fab")
		)
		(fp_line
			(start -0.12065 0.3048)
			(end -0.67945 0.3048)
			(stroke
				(width 0.1)
				(type default)
			)
			(layer "F.Fab")
		)
		(fp_line
			(start 0.120396 0.2794)
			(end -0.12065 0.2794)
			(stroke
				(width 0.1)
				(type default)
			)
			(layer "F.Fab")
		)
		(fp_line
			(start 0.120396 0.3048)
			(end 0.120396 0.2794)
			(stroke
				(width 0.1)
				(type default)
			)
			(layer "F.Fab")
		)
		(fp_line
			(start 0.12065 -0.3048)
			(end 0.67945 -0.3048)
			(stroke
				(width 0.1)
				(type default)
			)
			(layer "F.Fab")
		)
		(fp_line
			(start 0.12065 -0.2794)
			(end 0.12065 -0.3048)
			(stroke
				(width 0.1)
				(type default)
			)
			(layer "F.Fab")
		)
		(fp_line
			(start 0.67945 -0.3048)
			(end 0.67945 0.3048)
			(stroke
				(width 0.1)
				(type default)
			)
			(layer "F.Fab")
		)
		(fp_line
			(start 0.67945 0.3048)
			(end 0.120396 0.3048)
			(stroke
				(width 0.1)
				(type default)
			)
			(layer "F.Fab")
		)
		(pad "1" smd circle
			(at -0.40005 0)
			(size 0 0)
			(layers "F.Cu" "F.Mask" "F.Paste")
			(net "PEX3_SYS_ERR_N")
		)
		(pad "2" smd circle
			(at 0.40005 0)
			(size 0 0)
			(layers "F.Cu" "F.Mask" "F.Paste")
			(net "PEX3_SYS_ERR_R_N")
		)
	)
	(footprint ""
		(layer "F.Cu")
		(at 261.84987 -320.900044)
		(property "Reference" "H85"
			(at -6.472174 -7.562088 0)
			(unlocked yes)
			(layer "F.SilkS")
			(effects
				(font
					(size 0.7874 0.5842)
					(thickness 0.1524)
				)
				(justify left)
			)
		)
		(property "Value" ""
			(at 0 0 0)
			(layer "F.Fab")
			(effects
				(font
					(size 1.27 1.27)
				)
			)
		)
		(duplicate_pad_numbers_are_jumpers no)
		(fp_arc
			(start 5.559044 5.7531)
			(mid -7.365039 -3.124664)
			(end 7.999984 0)
			(stroke
				(width 0.1524)
				(type default)
			)
			(layer "F.SilkS")
		)
		(fp_arc
			(start 7.999984 0)
			(mid 7.999991 0.010414)
			(end 7.999984 0.020828)
			(stroke
				(width 0.1524)
				(type default)
			)
			(layer "F.SilkS")
		)
		(fp_arc
			(start 5.292598 5.998972)
			(mid -7.291736 -3.290917)
			(end 7.999984 0)
			(stroke
				(width 0.1524)
				(type default)
			)
			(layer "B.SilkS")
		)
		(fp_arc
			(start 7.999984 0)
			(mid 7.993019 0.334811)
			(end 7.972044 0.669036)
			(stroke
				(width 0.1524)
				(type default)
			)
			(layer "B.SilkS")
		)
		(fp_circle
			(center 0 0)
			(end 7.999984 0)
			(stroke
				(width 0.1)
				(type default)
			)
			(fill no)
			(layer "B.Fab")
		)
		(fp_circle
			(center 0 0)
			(end 7.999984 0)
			(stroke
				(width 0.1)
				(type default)
			)
			(fill no)
			(layer "F.Fab")
		)
		(pad "" np_thru_hole circle
			(at 0 0)
			(size 4.5212 4.5212)
			(drill 4.5212)
			(layers "*.Cu" "*.Mask")
			(clearance 0.381)
			(thermal_gap 0.381)
		)
		(pad "2" thru_hole circle
			(at 3.6322 0)
			(size 0.762 0.762)
			(drill 0.5588)
			(layers "*.Cu" "*.Mask")
			(remove_unused_layers no)
			(net "GND")
			(clearance 0.1524)
			(thermal_gap 0.1524)
		)
		(pad "3" thru_hole circle
			(at 2.568448 -2.568448)
			(size 0.762 0.762)
			(drill 0.5588)
			(layers "*.Cu" "*.Mask")
			(remove_unused_layers no)
			(net "GND")
			(clearance 0.1524)
			(thermal_gap 0.1524)
		)
		(pad "4" thru_hole circle
			(at 0 -3.6322)
			(size 0.762 0.762)
			(drill 0.5588)
			(layers "*.Cu" "*.Mask")
			(remove_unused_layers no)
			(net "GND")
			(clearance 0.1524)
			(thermal_gap 0.1524)
		)
		(pad "5" thru_hole circle
			(at -2.568448 -2.568448)
			(size 0.762 0.762)
			(drill 0.5588)
			(layers "*.Cu" "*.Mask")
			(remove_unused_layers no)
			(net "GND")
			(clearance 0.1524)
			(thermal_gap 0.1524)
		)
		(pad "6" thru_hole circle
			(at -3.6322 0)
			(size 0.762 0.762)
			(drill 0.5588)
			(layers "*.Cu" "*.Mask")
			(remove_unused_layers no)
			(net "GND")
			(clearance 0.1524)
			(thermal_gap 0.1524)
		)
		(pad "7" thru_hole circle
			(at -2.568448 2.568448)
			(size 0.762 0.762)
			(drill 0.5588)
			(layers "*.Cu" "*.Mask")
			(remove_unused_layers no)
			(net "GND")
			(clearance 0.1524)
			(thermal_gap 0.1524)
		)
		(pad "8" thru_hole circle
			(at 0 3.6322)
			(size 0.762 0.762)
			(drill 0.5588)
			(layers "*.Cu" "*.Mask")
			(remove_unused_layers no)
			(net "GND")
			(clearance 0.1524)
			(thermal_gap 0.1524)
		)
		(pad "9" thru_hole circle
			(at 2.568448 2.568448)
			(size 0.762 0.762)
			(drill 0.5588)
			(layers "*.Cu" "*.Mask")
			(remove_unused_layers no)
			(net "GND")
			(clearance 0.1524)
			(thermal_gap 0.1524)
		)
		(zone
			(layer "F.Cu")
			(hatch none 0.5)
			(connect_pads
				(clearance 0)
			)
			(min_thickness 0.25)
			(keepout
				(tracks not_allowed)
				(vias allowed)
				(pads allowed)
				(copperpour not_allowed)
				(footprints allowed)
			)
			(placement
				(enabled no)
				(sheetname "")
			)
			(fill
				(thermal_gap 0.5)
				(thermal_bridge_width 0.5)
				(island_removal_mode 0)
			)
			(polygon
				(pts
					(arc
						(start 261.84987 -312.90006)
						(mid 253.849886 -320.900044)
						(end 261.84987 -328.900028)
					)
					(arc
						(start 261.84987 -325.649844)
						(mid 257.10007 -320.900044)
						(end 261.84987 -316.150244)
					)
				)
			)
		)
		(zone
			(layer "F.Cu")
			(hatch none 0.5)
			(connect_pads
				(clearance 0)
			)
			(min_thickness 0.25)
			(keepout
				(tracks not_allowed)
				(vias allowed)
				(pads allowed)
				(copperpour not_allowed)
				(footprints allowed)
			)
			(placement
				(enabled no)
				(sheetname "")
			)
			(fill
				(thermal_gap 0.5)
				(thermal_bridge_width 0.5)
				(island_removal_mode 0)
			)
			(polygon
				(pts
					(arc
						(start 261.84987 -312.90006)
						(mid 269.849854 -320.900044)
						(end 261.84987 -328.900028)
					)
					(arc
						(start 261.84987 -325.649844)
						(mid 266.59967 -320.900044)
						(end 261.84987 -316.150244)
					)
				)
			)
		)
		(zone
			(layers "F.Cu" "B.Cu" "In1.Cu" "In2.Cu" "In3.Cu" "In4.Cu" "In5.Cu" "In6.Cu"
				"In7.Cu" "In8.Cu" "In9.Cu" "In10.Cu" "In11.Cu" "In12.Cu" "In13.Cu" "In14.Cu"
				"In15.Cu" "In16.Cu"
			)
			(hatch none 0.5)
			(connect_pads
				(clearance 0)
			)
			(min_thickness 0.25)
			(keepout
				(tracks not_allowed)
				(vias allowed)
				(pads allowed)
				(copperpour not_allowed)
				(footprints allowed)
			)
			(placement
				(enabled no)
				(sheetname "")
			)
			(fill
				(thermal_gap 0.5)
				(thermal_bridge_width 0.5)
				(island_removal_mode 0)
			)
			(polygon
				(pts
					(arc
						(start 264.61593 -320.900044)
						(mid 259.08381 -320.900044)
						(end 264.61593 -320.900044)
					)
				)
			)
		)
		(zone
			(layer "B.Cu")
			(hatch none 0.5)
			(connect_pads
				(clearance 0)
			)
			(min_thickness 0.25)
			(keepout
				(tracks not_allowed)
				(vias allowed)
				(pads allowed)
				(copperpour not_allowed)
				(footprints allowed)
			)
			(placement
				(enabled no)
				(sheetname "")
			)
			(fill
				(thermal_gap 0.5)
				(thermal_bridge_width 0.5)
				(island_removal_mode 0)
			)
			(polygon
				(pts
					(arc
						(start 261.84987 -315.896244)
						(mid 256.84607 -320.900044)
						(end 261.84987 -325.903844)
					)
					(arc
						(start 261.84987 -325.421244)
						(mid 257.32867 -320.900044)
						(end 261.84987 -316.378844)
					)
				)
			)
		)
		(zone
			(layer "B.Cu")
			(hatch none 0.5)
			(connect_pads
				(clearance 0)
			)
			(min_thickness 0.25)
			(keepout
				(tracks not_allowed)
				(vias allowed)
				(pads allowed)
				(copperpour not_allowed)
				(footprints allowed)
			)
			(placement
				(enabled no)
				(sheetname "")
			)
			(fill
				(thermal_gap 0.5)
				(thermal_bridge_width 0.5)
				(island_removal_mode 0)
			)
			(polygon
				(pts
					(arc
						(start 261.84987 -315.896244)
						(mid 266.85367 -320.900044)
						(end 261.84987 -325.903844)
					)
					(arc
						(start 261.84987 -325.421244)
						(mid 266.37107 -320.900044)
						(end 261.84987 -316.378844)
					)
				)
			)
		)
	)
)
